# T6G (Grand Teton) — schematic netlist excerpt (pin names and nets, part order shuffled) for the footprints in the layout excerpt that follows; sources: Cadence DE-HDL packaged netlist, KiCad conversion of 04192023_DAF0TMB3IC0_F0TG_MB_C_brd_V02_OCP.brd

C2114  Q_CAP  22UF 4V 20% X6S  pkg C0402  page 74 : A = PVDD11_S3_P1 ; B = GND
C145  Q_CAP  10UF 25V 10% X6S  pkg C0805  page 87 : A = P12V_MEM_CPU0 ; B = GND
C2651  Q_CAP  22UF 4V 20% X6S  pkg C0402  page 70 : A = PVDD11_S3_P0 ; B = GND

(kicad_pcb
	(version 20260206)
	(generator "pcbnew")
	(generator_version "10.0")
	(general
		(thickness 1.6)
		(legacy_teardrops no)
	)
	(paper "A4")
	(title_block
		(title "04192023_DAF0TMB3IC0_F0TG_MB_C_brd_V02_OCP.brd")
		(comment 1 "Grand Teton / footprints 6815-6817 of 8354")
	)
	(layers
		(0 "F.Cu" signal "TOP")
		(4 "In1.Cu" signal "GND")
		(6 "In2.Cu" signal "IN1")
		(8 "In3.Cu" signal "GND1")
		(10 "In4.Cu" signal "IN2")
		(12 "In5.Cu" signal "GND2")
		(14 "In6.Cu" signal "IN3")
		(16 "In7.Cu" signal "GND3")
		(18 "In8.Cu" signal "VCC")
		(20 "In9.Cu" signal "VCC1")
		(22 "In10.Cu" signal "GND4")
		(24 "In11.Cu" signal "IN4")
		(26 "In12.Cu" signal "GND5")
		(28 "In13.Cu" signal "IN5")
		(30 "In14.Cu" signal "GND6")
		(32 "In15.Cu" signal "IN6")
		(34 "In16.Cu" signal "GND7")
		(2 "B.Cu" signal "BOTTOM")
		(9 "F.Adhes" user "F.Adhesive")
		(11 "B.Adhes" user "B.Adhesive")
		(13 "F.Paste" user "Package Geometry/Pastemask Top")
		(15 "B.Paste" user "Package Geometry/Pastemask Bottom")
		(5 "F.SilkS" user "Ref Des/Silkscreen Top")
		(7 "B.SilkS" user "Ref Des/Silkscreen Bottom")
		(1 "F.Mask" user "Board Geometry/Soldermask Top")
		(3 "B.Mask" user "Board Geometry/Soldermask Bottom")
		(17 "Dwgs.User" user "User.Drawings")
		(19 "Cmts.User" user "User.Comments")
		(21 "Eco1.User" user "User.Eco1")
		(23 "Eco2.User" user "User.Eco2")
		(25 "Edge.Cuts" user "Board Geometry/Outline")
		(27 "Margin" user)
		(31 "F.CrtYd" user "Package Geometry/Place Bound Top")
		(29 "B.CrtYd" user "Package Geometry/Place Bound Bottom")
		(35 "F.Fab" user "Ref Des/Assembly Top")
		(33 "B.Fab" user "Ref Des/Assembly Bottom")
	)
	(footprint ""
		(layer "B.Cu")
		(at 121.452386 -264.354564)
		(property "Reference" "C2114"
			(at 0 0 0)
			(layer "B.SilkS")
			(hide yes)
			(effects
				(font
					(size 1.27 1.27)
				)
				(justify mirror)
			)
		)
		(property "Value" ""
			(at 0 0 0)
			(layer "B.Fab")
			(effects
				(font
					(size 1.27 1.27)
				)
				(justify mirror)
			)
		)
		(duplicate_pad_numbers_are_jumpers no)
		(fp_line
			(start -0.7874 -0.4064)
			(end -0.7874 0.4064)
			(stroke
				(width 0.1524)
				(type default)
			)
			(layer "B.SilkS")
		)
		(fp_line
			(start -0.7874 0.4064)
			(end 0.7874 0.4064)
			(stroke
				(width 0.1524)
				(type default)
			)
			(layer "B.SilkS")
		)
		(fp_line
			(start 0.7874 -0.4064)
			(end -0.7874 -0.4064)
			(stroke
				(width 0.1524)
				(type default)
			)
			(layer "B.SilkS")
		)
		(fp_line
			(start 0.7874 0.4064)
			(end 0.7874 -0.4064)
			(stroke
				(width 0.1524)
				(type default)
			)
			(layer "B.SilkS")
		)
		(fp_line
			(start -0.67945 -0.3048)
			(end -0.67945 0.3048)
			(stroke
				(width 0.1)
				(type default)
			)
			(layer "B.Fab")
		)
		(fp_line
			(start -0.67945 0.3048)
			(end -0.120396 0.3048)
			(stroke
				(width 0.1)
				(type default)
			)
			(layer "B.Fab")
		)
		(fp_line
			(start -0.12065 -0.3048)
			(end -0.67945 -0.3048)
			(stroke
				(width 0.1)
				(type default)
			)
			(layer "B.Fab")
		)
		(fp_line
			(start -0.12065 -0.2794)
			(end -0.12065 -0.3048)
			(stroke
				(width 0.1)
				(type default)
			)
			(layer "B.Fab")
		)
		(fp_line
			(start -0.120396 0.2794)
			(end 0.12065 0.2794)
			(stroke
				(width 0.1)
				(type default)
			)
			(layer "B.Fab")
		)
		(fp_line
			(start -0.120396 0.3048)
			(end -0.120396 0.2794)
			(stroke
				(width 0.1)
				(type default)
			)
			(layer "B.Fab")
		)
		(fp_line
			(start 0.12065 -0.305054)
			(end 0.12065 -0.2794)
			(stroke
				(width 0.1)
				(type default)
			)
			(layer "B.Fab")
		)
		(fp_line
			(start 0.12065 -0.2794)
			(end -0.12065 -0.2794)
			(stroke
				(width 0.1)
				(type default)
			)
			(layer "B.Fab")
		)
		(fp_line
			(start 0.12065 0.2794)
			(end 0.12065 0.3048)
			(stroke
				(width 0.1)
				(type default)
			)
			(layer "B.Fab")
		)
		(fp_line
			(start 0.12065 0.3048)
			(end 0.67945 0.3048)
			(stroke
				(width 0.1)
				(type default)
			)
			(layer "B.Fab")
		)
		(fp_line
			(start 0.67945 -0.305054)
			(end 0.12065 -0.305054)
			(stroke
				(width 0.1)
				(type default)
			)
			(layer "B.Fab")
		)
		(fp_line
			(start 0.67945 0.3048)
			(end 0.67945 -0.305054)
			(stroke
				(width 0.1)
				(type default)
			)
			(layer "B.Fab")
		)
		(pad "1" smd circle
			(at 0.40005 0 180)
			(size 0 0)
			(layers "B.Cu" "B.Mask" "B.Paste")
			(net "PVDD11_S3_P1")
		)
		(pad "2" smd circle
			(at -0.40005 0 180)
			(size 0 0)
			(layers "B.Cu" "B.Mask" "B.Paste")
			(net "GND")
		)
	)
	(footprint ""
		(layer "B.Cu")
		(at 371.297454 -264.35431)
		(property "Reference" "C2651"
			(at 0 0 0)
			(layer "B.SilkS")
			(hide yes)
			(effects
				(font
					(size 1.27 1.27)
				)
				(justify mirror)
			)
		)
		(property "Value" ""
			(at 0 0 0)
			(layer "B.Fab")
			(effects
				(font
					(size 1.27 1.27)
				)
				(justify mirror)
			)
		)
		(duplicate_pad_numbers_are_jumpers no)
		(fp_line
			(start -0.7874 -0.4064)
			(end -0.7874 0.4064)
			(stroke
				(width 0.1524)
				(type default)
			)
			(layer "B.SilkS")
		)
		(fp_line
			(start -0.7874 0.4064)
			(end 0.7874 0.4064)
			(stroke
				(width 0.1524)
				(type default)
			)
			(layer "B.SilkS")
		)
		(fp_line
			(start 0.7874 -0.4064)
			(end -0.7874 -0.4064)
			(stroke
				(width 0.1524)
				(type default)
			)
			(layer "B.SilkS")
		)
		(fp_line
			(start 0.7874 0.4064)
			(end 0.7874 -0.4064)
			(stroke
				(width 0.1524)
				(type default)
			)
			(layer "B.SilkS")
		)
		(fp_line
			(start -0.67945 -0.3048)
			(end -0.67945 0.3048)
			(stroke
				(width 0.1)
				(type default)
			)
			(layer "B.Fab")
		)
		(fp_line
			(start -0.67945 0.3048)
			(end -0.120396 0.3048)
			(stroke
				(width 0.1)
				(type default)
			)
			(layer "B.Fab")
		)
		(fp_line
			(start -0.12065 -0.3048)
			(end -0.67945 -0.3048)
			(stroke
				(width 0.1)
				(type default)
			)
			(layer "B.Fab")
		)
		(fp_line
			(start -0.12065 -0.2794)
			(end -0.12065 -0.3048)
			(stroke
				(width 0.1)
				(type default)
			)
			(layer "B.Fab")
		)
		(fp_line
			(start -0.120396 0.2794)
			(end 0.12065 0.2794)
			(stroke
				(width 0.1)
				(type default)
			)
			(layer "B.Fab")
		)
		(fp_line
			(start -0.120396 0.3048)
			(end -0.120396 0.2794)
			(stroke
				(width 0.1)
				(type default)
			)
			(layer "B.Fab")
		)
		(fp_line
			(start 0.12065 -0.305054)
			(end 0.12065 -0.2794)
			(stroke
				(width 0.1)
				(type default)
			)
			(layer "B.Fab")
		)
		(fp_line
			(start 0.12065 -0.2794)
			(end -0.12065 -0.2794)
			(stroke
				(width 0.1)
				(type default)
			)
			(layer "B.Fab")
		)
		(fp_line
			(start 0.12065 0.2794)
			(end 0.12065 0.3048)
			(stroke
				(width 0.1)
				(type default)
			)
			(layer "B.Fab")
		)
		(fp_line
			(start 0.12065 0.3048)
			(end 0.67945 0.3048)
			(stroke
				(width 0.1)
				(type default)
			)
			(layer "B.Fab")
		)
		(fp_line
			(start 0.67945 -0.305054)
			(end 0.12065 -0.305054)
			(stroke
				(width 0.1)
				(type default)
			)
			(layer "B.Fab")
		)
		(fp_line
			(start 0.67945 0.3048)
			(end 0.67945 -0.305054)
			(stroke
				(width 0.1)
				(type default)
			)
			(layer "B.Fab")
		)
		(pad "1" smd circle
			(at 0.40005 0 180)
			(size 0 0)
			(layers "B.Cu" "B.Mask" "B.Paste")
			(net "PVDD11_S3_P0")
		)
		(pad "2" smd circle
			(at -0.40005 0 180)
			(size 0 0)
			(layers "B.Cu" "B.Mask" "B.Paste")
			(net "GND")
		)
	)
	(footprint ""
		(layer "B.Cu")
		(at 295.724072 -192.660016 180)
		(property "Reference" "C145"
			(at 0 0 0)
			(layer "B.SilkS")
			(hide yes)
			(effects
				(font
					(size 1.27 1.27)
				)
				(justify mirror)
			)
		)
		(property "Value" ""
			(at 0 0 0)
			(layer "B.Fab")
			(effects
				(font
					(size 1.27 1.27)
				)
				(justify mirror)
			)
		)
		(duplicate_pad_numbers_are_jumpers no)
		(fp_line
			(start 1.524 0.762)
			(end 1.524 -0.762)
			(stroke
				(width 0.1524)
				(type default)
			)
			(layer "B.SilkS")
		)
		(fp_line
			(start 1.524 -0.762)
			(end -1.524 -0.762)
			(stroke
				(width 0.1524)
				(type default)
			)
			(layer "B.SilkS")
		)
		(fp_line
			(start -1.524 0.762)
			(end 1.524 0.762)
			(stroke
				(width 0.1524)
				(type default)
			)
			(layer "B.SilkS")
		)
		(fp_line
			(start -1.524 -0.762)
			(end -1.524 0.762)
			(stroke
				(width 0.1524)
				(type default)
			)
			(layer "B.SilkS")
		)
		(fp_line
			(start 1.1049 0.724916)
			(end -1.1049 0.724916)
			(stroke
				(width 0.1)
				(type default)
			)
			(layer "B.Fab")
		)
		(fp_line
			(start 1.1049 -0.724916)
			(end 1.1049 0.724916)
			(stroke
				(width 0.1)
				(type default)
			)
			(layer "B.Fab")
		)
		(fp_line
			(start -1.1049 0.724916)
			(end -1.1049 -0.724916)
			(stroke
				(width 0.1)
				(type default)
			)
			(layer "B.Fab")
		)
		(fp_line
			(start -1.1049 -0.724916)
			(end 1.1049 -0.724916)
			(stroke
				(width 0.1)
				(type default)
			)
			(layer "B.Fab")
		)
		(pad "1" smd rect
			(at 0.889 0 180)
			(size 1.016 1.27)
			(layers "B.Cu" "B.Mask" "B.Paste")
			(net "P12V_MEM_CPU0")
		)
		(pad "2" smd rect
			(at -0.889 0 180)
			(size 1.016 1.27)
			(layers "B.Cu" "B.Mask" "B.Paste")
			(net "GND")
		)
	)
)
